(kicad_pcb
	(version 20260206)
	(generator "pcbnew")
	(generator_version "10.0")
	(general
		(thickness 1.6)
		(legacy_teardrops no)
	)
	(paper "A4")
	(title_block
		(title "03242023_DA0F0TMBIJ0_F0T_Motherboard_J_brd_V01_OCP.brd")
		(comment 1 "Grand Teton / footprints 4577-4583 of 6105")
	)
	(layers
		(0 "F.Cu" signal "TOP")
		(4 "In1.Cu" signal "GND")
		(6 "In2.Cu" signal "IN1")
		(8 "In3.Cu" signal "GND1")
		(10 "In4.Cu" signal "IN2")
		(12 "In5.Cu" signal "GND2")
		(14 "In6.Cu" signal "IN3")
		(16 "In7.Cu" signal "GND3")
		(18 "In8.Cu" signal "VCC")
		(20 "In9.Cu" signal "VCC1")
		(22 "In10.Cu" signal "GND4")
		(24 "In11.Cu" signal "IN4")
		(26 "In12.Cu" signal "GND5")
		(28 "In13.Cu" signal "IN5")
		(30 "In14.Cu" signal "GND6")
		(32 "In15.Cu" signal "IN6")
		(34 "In16.Cu" signal "GND7")
		(2 "B.Cu" signal "BOTTOM")
		(9 "F.Adhes" user "F.Adhesive")
		(11 "B.Adhes" user "B.Adhesive")
		(13 "F.Paste" user "Package Geometry/Pastemask Top")
		(15 "B.Paste" user "Package Geometry/Pastemask Bottom")
		(5 "F.SilkS" user "Ref Des/Silkscreen Top")
		(7 "B.SilkS" user "Ref Des/Silkscreen Bottom")
		(1 "F.Mask" user "Board Geometry/Soldermask Top")
		(3 "B.Mask" user "Board Geometry/Soldermask Bottom")
		(17 "Dwgs.User" user "User.Drawings")
		(19 "Cmts.User" user "User.Comments")
		(21 "Eco1.User" user "User.Eco1")
		(23 "Eco2.User" user "User.Eco2")
		(25 "Edge.Cuts" user "Board Geometry/Outline")
		(27 "Margin" user)
		(31 "F.CrtYd" user "Package Geometry/Place Bound Top")
		(29 "B.CrtYd" user "Package Geometry/Place Bound Bottom")
		(35 "F.Fab" user "Ref Des/Assembly Top")
		(33 "B.Fab" user "Ref Des/Assembly Bottom")
	)
	(footprint ""
		(layer "B.Cu")
		(at 430.600104 -138.558778)
		(property "Reference" "R2397"
			(at 0 0 0)
			(layer "B.SilkS")
			(hide yes)
			(effects
				(font
					(size 1.27 1.27)
				)
				(justify mirror)
			)
		)
		(property "Value" ""
			(at 0 0 0)
			(layer "B.Fab")
			(effects
				(font
					(size 1.27 1.27)
				)
				(justify mirror)
			)
		)
		(duplicate_pad_numbers_are_jumpers no)
		(fp_line
			(start -0.7874 -0.4064)
			(end -0.7874 0.4064)
			(stroke
				(width 0.1524)
				(type default)
			)
			(layer "B.SilkS")
		)
		(fp_line
			(start -0.7874 0.4064)
			(end 0.7874 0.4064)
			(stroke
				(width 0.1524)
				(type default)
			)
			(layer "B.SilkS")
		)
		(fp_line
			(start 0.7874 -0.4064)
			(end -0.7874 -0.4064)
			(stroke
				(width 0.1524)
				(type default)
			)
			(layer "B.SilkS")
		)
		(fp_line
			(start 0.7874 0.4064)
			(end 0.7874 -0.4064)
			(stroke
				(width 0.1524)
				(type default)
			)
			(layer "B.SilkS")
		)
		(fp_line
			(start -0.67945 -0.3048)
			(end -0.67945 0.3048)
			(stroke
				(width 0.1)
				(type default)
			)
			(layer "B.Fab")
		)
		(fp_line
			(start -0.67945 0.3048)
			(end -0.120396 0.3048)
			(stroke
				(width 0.1)
				(type default)
			)
			(layer "B.Fab")
		)
		(fp_line
			(start -0.12065 -0.3048)
			(end -0.67945 -0.3048)
			(stroke
				(width 0.1)
				(type default)
			)
			(layer "B.Fab")
		)
		(fp_line
			(start -0.12065 -0.2794)
			(end -0.12065 -0.3048)
			(stroke
				(width 0.1)
				(type default)
			)
			(layer "B.Fab")
		)
		(fp_line
			(start -0.120396 0.2794)
			(end 0.12065 0.2794)
			(stroke
				(width 0.1)
				(type default)
			)
			(layer "B.Fab")
		)
		(fp_line
			(start -0.120396 0.3048)
			(end -0.120396 0.2794)
			(stroke
				(width 0.1)
				(type default)
			)
			(layer "B.Fab")
		)
		(fp_line
			(start 0.12065 -0.305054)
			(end 0.12065 -0.2794)
			(stroke
				(width 0.1)
				(type default)
			)
			(layer "B.Fab")
		)
		(fp_line
			(start 0.12065 -0.2794)
			(end -0.12065 -0.2794)
			(stroke
				(width 0.1)
				(type default)
			)
			(layer "B.Fab")
		)
		(fp_line
			(start 0.12065 0.2794)
			(end 0.12065 0.3048)
			(stroke
				(width 0.1)
				(type default)
			)
			(layer "B.Fab")
		)
		(fp_line
			(start 0.12065 0.3048)
			(end 0.67945 0.3048)
			(stroke
				(width 0.1)
				(type default)
			)
			(layer "B.Fab")
		)
		(fp_line
			(start 0.67945 -0.305054)
			(end 0.12065 -0.305054)
			(stroke
				(width 0.1)
				(type default)
			)
			(layer "B.Fab")
		)
		(fp_line
			(start 0.67945 0.3048)
			(end 0.67945 -0.305054)
			(stroke
				(width 0.1)
				(type default)
			)
			(layer "B.Fab")
		)
		(pad "1" smd circle
			(at 0.40005 0 180)
			(size 0 0)
			(layers "B.Cu" "B.Mask" "B.Paste")
			(net "PWRGD_PVCCFA_EHV_CPU0")
		)
		(pad "2" smd circle
			(at -0.40005 0 180)
			(size 0 0)
			(layers "B.Cu" "B.Mask" "B.Paste")
			(net "PWRGD_PVCCFA_EHV_CPU0_R")
		)
	)
	(footprint ""
		(layer "B.Cu")
		(at 64.546988 -8.98398 90)
		(property "Reference" "C1835"
			(at 0 0 90)
			(layer "B.SilkS")
			(hide yes)
			(effects
				(font
					(size 1.27 1.27)
				)
				(justify mirror)
			)
		)
		(property "Value" ""
			(at 0 0 90)
			(layer "B.Fab")
			(effects
				(font
					(size 1.27 1.27)
				)
				(justify mirror)
			)
		)
		(duplicate_pad_numbers_are_jumpers no)
		(fp_line
			(start 0.7874 -0.4064)
			(end -0.7874 -0.4064)
			(stroke
				(width 0.1524)
				(type default)
			)
			(layer "B.SilkS")
		)
		(fp_line
			(start -0.7874 -0.4064)
			(end -0.7874 0.4064)
			(stroke
				(width 0.1524)
				(type default)
			)
			(layer "B.SilkS")
		)
		(fp_line
			(start 0.7874 0.4064)
			(end 0.7874 -0.4064)
			(stroke
				(width 0.1524)
				(type default)
			)
			(layer "B.SilkS")
		)
		(fp_line
			(start -0.7874 0.4064)
			(end 0.7874 0.4064)
			(stroke
				(width 0.1524)
				(type default)
			)
			(layer "B.SilkS")
		)
		(fp_line
			(start 0.67945 -0.305054)
			(end 0.12065 -0.305054)
			(stroke
				(width 0.1)
				(type default)
			)
			(layer "B.Fab")
		)
		(fp_line
			(start 0.12065 -0.305054)
			(end 0.12065 -0.2794)
			(stroke
				(width 0.1)
				(type default)
			)
			(layer "B.Fab")
		)
		(fp_line
			(start -0.12065 -0.3048)
			(end -0.67945 -0.3048)
			(stroke
				(width 0.1)
				(type default)
			)
			(layer "B.Fab")
		)
		(fp_line
			(start -0.67945 -0.3048)
			(end -0.67945 0.3048)
			(stroke
				(width 0.1)
				(type default)
			)
			(layer "B.Fab")
		)
		(fp_line
			(start 0.12065 -0.2794)
			(end -0.12065 -0.2794)
			(stroke
				(width 0.1)
				(type default)
			)
			(layer "B.Fab")
		)
		(fp_line
			(start -0.12065 -0.2794)
			(end -0.12065 -0.3048)
			(stroke
				(width 0.1)
				(type default)
			)
			(layer "B.Fab")
		)
		(fp_line
			(start 0.12065 0.2794)
			(end 0.12065 0.3048)
			(stroke
				(width 0.1)
				(type default)
			)
			(layer "B.Fab")
		)
		(fp_line
			(start -0.120396 0.2794)
			(end 0.12065 0.2794)
			(stroke
				(width 0.1)
				(type default)
			)
			(layer "B.Fab")
		)
		(fp_line
			(start 0.67945 0.3048)
			(end 0.67945 -0.305054)
			(stroke
				(width 0.1)
				(type default)
			)
			(layer "B.Fab")
		)
		(fp_line
			(start 0.12065 0.3048)
			(end 0.67945 0.3048)
			(stroke
				(width 0.1)
				(type default)
			)
			(layer "B.Fab")
		)
		(fp_line
			(start -0.120396 0.3048)
			(end -0.120396 0.2794)
			(stroke
				(width 0.1)
				(type default)
			)
			(layer "B.Fab")
		)
		(fp_line
			(start -0.67945 0.3048)
			(end -0.120396 0.3048)
			(stroke
				(width 0.1)
				(type default)
			)
			(layer "B.Fab")
		)
		(pad "1" smd circle
			(at 0.40005 0 270)
			(size 0 0)
			(layers "B.Cu" "B.Mask" "B.Paste")
			(net "P3V3_OCP_V3_2")
		)
		(pad "2" smd circle
			(at -0.40005 0 270)
			(size 0 0)
			(layers "B.Cu" "B.Mask" "B.Paste")
			(net "GND")
		)
	)
	(footprint ""
		(layer "B.Cu")
		(at 8.153146 -321.554856 -90)
		(property "Reference" "C70"
			(at 0 0 90)
			(layer "B.SilkS")
			(hide yes)
			(effects
				(font
					(size 1.27 1.27)
				)
				(justify mirror)
			)
		)
		(property "Value" ""
			(at 0 0 90)
			(layer "B.Fab")
			(effects
				(font
					(size 1.27 1.27)
				)
				(justify mirror)
			)
		)
		(duplicate_pad_numbers_are_jumpers no)
		(fp_line
			(start -1.524 0.762)
			(end 1.524 0.762)
			(stroke
				(width 0.1524)
				(type default)
			)
			(layer "B.SilkS")
		)
		(fp_line
			(start 1.524 0.762)
			(end 1.524 -0.762)
			(stroke
				(width 0.1524)
				(type default)
			)
			(layer "B.SilkS")
		)
		(fp_line
			(start -1.524 -0.762)
			(end -1.524 0.762)
			(stroke
				(width 0.1524)
				(type default)
			)
			(layer "B.SilkS")
		)
		(fp_line
			(start 1.524 -0.762)
			(end -1.524 -0.762)
			(stroke
				(width 0.1524)
				(type default)
			)
			(layer "B.SilkS")
		)
		(fp_line
			(start -1.1049 0.724916)
			(end -1.1049 -0.724916)
			(stroke
				(width 0.1)
				(type default)
			)
			(layer "B.Fab")
		)
		(fp_line
			(start 1.1049 0.724916)
			(end -1.1049 0.724916)
			(stroke
				(width 0.1)
				(type default)
			)
			(layer "B.Fab")
		)
		(fp_line
			(start -1.1049 -0.724916)
			(end 1.1049 -0.724916)
			(stroke
				(width 0.1)
				(type default)
			)
			(layer "B.Fab")
		)
		(fp_line
			(start 1.1049 -0.724916)
			(end 1.1049 0.724916)
			(stroke
				(width 0.1)
				(type default)
			)
			(layer "B.Fab")
		)
		(pad "1" smd rect
			(at 0.889 0 270)
			(size 1.016 1.27)
			(layers "B.Cu" "B.Mask" "B.Paste")
			(net "P12V_S3_AUX_CPU1_NVDIMM")
		)
		(pad "2" smd rect
			(at -0.889 0 270)
			(size 1.016 1.27)
			(layers "B.Cu" "B.Mask" "B.Paste")
			(net "GND")
		)
	)
	(footprint ""
		(layer "B.Cu")
		(at 39.3954 -436.646828 -90)
		(property "Reference" "R4603"
			(at 0 0 90)
			(layer "B.SilkS")
			(hide yes)
			(effects
				(font
					(size 1.27 1.27)
				)
				(justify mirror)
			)
		)
		(property "Value" ""
			(at 0 0 90)
			(layer "B.Fab")
			(effects
				(font
					(size 1.27 1.27)
				)
				(justify mirror)
			)
		)
		(duplicate_pad_numbers_are_jumpers no)
		(fp_line
			(start -0.7874 0.4064)
			(end 0.7874 0.4064)
			(stroke
				(width 0.1524)
				(type default)
			)
			(layer "B.SilkS")
		)
		(fp_line
			(start 0.7874 0.4064)
			(end 0.7874 -0.4064)
			(stroke
				(width 0.1524)
				(type default)
			)
			(layer "B.SilkS")
		)
		(fp_line
			(start -0.7874 -0.4064)
			(end -0.7874 0.4064)
			(stroke
				(width 0.1524)
				(type default)
			)
			(layer "B.SilkS")
		)
		(fp_line
			(start 0.7874 -0.4064)
			(end -0.7874 -0.4064)
			(stroke
				(width 0.1524)
				(type default)
			)
			(layer "B.SilkS")
		)
		(fp_line
			(start -0.67945 0.3048)
			(end -0.120396 0.3048)
			(stroke
				(width 0.1)
				(type default)
			)
			(layer "B.Fab")
		)
		(fp_line
			(start -0.120396 0.3048)
			(end -0.120396 0.2794)
			(stroke
				(width 0.1)
				(type default)
			)
			(layer "B.Fab")
		)
		(fp_line
			(start 0.12065 0.3048)
			(end 0.67945 0.3048)
			(stroke
				(width 0.1)
				(type default)
			)
			(layer "B.Fab")
		)
		(fp_line
			(start 0.67945 0.3048)
			(end 0.67945 -0.305054)
			(stroke
				(width 0.1)
				(type default)
			)
			(layer "B.Fab")
		)
		(fp_line
			(start -0.120396 0.2794)
			(end 0.12065 0.2794)
			(stroke
				(width 0.1)
				(type default)
			)
			(layer "B.Fab")
		)
		(fp_line
			(start 0.12065 0.2794)
			(end 0.12065 0.3048)
			(stroke
				(width 0.1)
				(type default)
			)
			(layer "B.Fab")
		)
		(fp_line
			(start -0.12065 -0.2794)
			(end -0.12065 -0.3048)
			(stroke
				(width 0.1)
				(type default)
			)
			(layer "B.Fab")
		)
		(fp_line
			(start 0.12065 -0.2794)
			(end -0.12065 -0.2794)
			(stroke
				(width 0.1)
				(type default)
			)
			(layer "B.Fab")
		)
		(fp_line
			(start -0.67945 -0.3048)
			(end -0.67945 0.3048)
			(stroke
				(width 0.1)
				(type default)
			)
			(layer "B.Fab")
		)
		(fp_line
			(start -0.12065 -0.3048)
			(end -0.67945 -0.3048)
			(stroke
				(width 0.1)
				(type default)
			)
			(layer "B.Fab")
		)
		(fp_line
			(start 0.12065 -0.305054)
			(end 0.12065 -0.2794)
			(stroke
				(width 0.1)
				(type default)
			)
			(layer "B.Fab")
		)
		(fp_line
			(start 0.67945 -0.305054)
			(end 0.12065 -0.305054)
			(stroke
				(width 0.1)
				(type default)
			)
			(layer "B.Fab")
		)
		(pad "1" smd circle
			(at 0.40005 0 90)
			(size 0 0)
			(layers "B.Cu" "B.Mask" "B.Paste")
			(net "SMB_BMC_GPU_EN")
		)
		(pad "2" smd circle
			(at -0.40005 0 90)
			(size 0 0)
			(layers "B.Cu" "B.Mask" "B.Paste")
			(net "GND")
		)
	)
	(footprint ""
		(layer "B.Cu")
		(at 42.814748 -100.584762 -90)
		(property "Reference" "C2195"
			(at 0 0 90)
			(layer "B.SilkS")
			(hide yes)
			(effects
				(font
					(size 1.27 1.27)
				)
				(justify mirror)
			)
		)
		(property "Value" ""
			(at 0 0 90)
			(layer "B.Fab")
			(effects
				(font
					(size 1.27 1.27)
				)
				(justify mirror)
			)
		)
		(duplicate_pad_numbers_are_jumpers no)
		(fp_line
			(start -0.7874 0.4064)
			(end 0.7874 0.4064)
			(stroke
				(width 0.1524)
				(type default)
			)
			(layer "B.SilkS")
		)
		(fp_line
			(start 0.7874 0.4064)
			(end 0.7874 -0.4064)
			(stroke
				(width 0.1524)
				(type default)
			)
			(layer "B.SilkS")
		)
		(fp_line
			(start -0.7874 -0.4064)
			(end -0.7874 0.4064)
			(stroke
				(width 0.1524)
				(type default)
			)
			(layer "B.SilkS")
		)
		(fp_line
			(start 0.7874 -0.4064)
			(end -0.7874 -0.4064)
			(stroke
				(width 0.1524)
				(type default)
			)
			(layer "B.SilkS")
		)
		(fp_line
			(start -0.67945 0.3048)
			(end -0.120396 0.3048)
			(stroke
				(width 0.1)
				(type default)
			)
			(layer "B.Fab")
		)
		(fp_line
			(start -0.120396 0.3048)
			(end -0.120396 0.2794)
			(stroke
				(width 0.1)
				(type default)
			)
			(layer "B.Fab")
		)
		(fp_line
			(start 0.12065 0.3048)
			(end 0.67945 0.3048)
			(stroke
				(width 0.1)
				(type default)
			)
			(layer "B.Fab")
		)
		(fp_line
			(start 0.67945 0.3048)
			(end 0.67945 -0.305054)
			(stroke
				(width 0.1)
				(type default)
			)
			(layer "B.Fab")
		)
		(fp_line
			(start -0.120396 0.2794)
			(end 0.12065 0.2794)
			(stroke
				(width 0.1)
				(type default)
			)
			(layer "B.Fab")
		)
		(fp_line
			(start 0.12065 0.2794)
			(end 0.12065 0.3048)
			(stroke
				(width 0.1)
				(type default)
			)
			(layer "B.Fab")
		)
		(fp_line
			(start -0.12065 -0.2794)
			(end -0.12065 -0.3048)
			(stroke
				(width 0.1)
				(type default)
			)
			(layer "B.Fab")
		)
		(fp_line
			(start 0.12065 -0.2794)
			(end -0.12065 -0.2794)
			(stroke
				(width 0.1)
				(type default)
			)
			(layer "B.Fab")
		)
		(fp_line
			(start -0.67945 -0.3048)
			(end -0.67945 0.3048)
			(stroke
				(width 0.1)
				(type default)
			)
			(layer "B.Fab")
		)
		(fp_line
			(start -0.12065 -0.3048)
			(end -0.67945 -0.3048)
			(stroke
				(width 0.1)
				(type default)
			)
			(layer "B.Fab")
		)
		(fp_line
			(start 0.12065 -0.305054)
			(end 0.12065 -0.2794)
			(stroke
				(width 0.1)
				(type default)
			)
			(layer "B.Fab")
		)
		(fp_line
			(start 0.67945 -0.305054)
			(end 0.12065 -0.305054)
			(stroke
				(width 0.1)
				(type default)
			)
			(layer "B.Fab")
		)
		(pad "1" smd circle
			(at 0.40005 0 90)
			(size 0 0)
			(layers "B.Cu" "B.Mask" "B.Paste")
			(net "P12V_E1S_0_ISENSE_MAM")
		)
		(pad "2" smd circle
			(at -0.40005 0 90)
			(size 0 0)
			(layers "B.Cu" "B.Mask" "B.Paste")
			(net "GND")
		)
	)
	(footprint ""
		(layer "B.Cu")
		(at 238.064294 -247.691148 180)
		(property "Reference" "C1883"
			(at 0 0 0)
			(layer "B.SilkS")
			(hide yes)
			(effects
				(font
					(size 1.27 1.27)
				)
				(justify mirror)
			)
		)
		(property "Value" ""
			(at 0 0 0)
			(layer "B.Fab")
			(effects
				(font
					(size 1.27 1.27)
				)
				(justify mirror)
			)
		)
		(duplicate_pad_numbers_are_jumpers no)
		(fp_line
			(start 1.524 0.762)
			(end 1.524 -0.762)
			(stroke
				(width 0.1524)
				(type default)
			)
			(layer "B.SilkS")
		)
		(fp_line
			(start 1.524 -0.762)
			(end -1.524 -0.762)
			(stroke
				(width 0.1524)
				(type default)
			)
			(layer "B.SilkS")
		)
		(fp_line
			(start -1.524 0.762)
			(end 1.524 0.762)
			(stroke
				(width 0.1524)
				(type default)
			)
			(layer "B.SilkS")
		)
		(fp_line
			(start -1.524 -0.762)
			(end -1.524 0.762)
			(stroke
				(width 0.1524)
				(type default)
			)
			(layer "B.SilkS")
		)
		(fp_line
			(start 1.1049 0.724916)
			(end -1.1049 0.724916)
			(stroke
				(width 0.1)
				(type default)
			)
			(layer "B.Fab")
		)
		(fp_line
			(start 1.1049 -0.724916)
			(end 1.1049 0.724916)
			(stroke
				(width 0.1)
				(type default)
			)
			(layer "B.Fab")
		)
		(fp_line
			(start -1.1049 0.724916)
			(end -1.1049 -0.724916)
			(stroke
				(width 0.1)
				(type default)
			)
			(layer "B.Fab")
		)
		(fp_line
			(start -1.1049 -0.724916)
			(end 1.1049 -0.724916)
			(stroke
				(width 0.1)
				(type default)
			)
			(layer "B.Fab")
		)
		(pad "1" smd rect
			(at 0.889 0 180)
			(size 1.016 1.27)
			(layers "B.Cu" "B.Mask" "B.Paste")
			(net "VFG3P3_CLK_GEN")
		)
		(pad "2" smd rect
			(at -0.889 0 180)
			(size 1.016 1.27)
			(layers "B.Cu" "B.Mask" "B.Paste")
			(net "GND")
		)
	)
	(footprint ""
		(layer "B.Cu")
		(at 435.549802 -10.072116 180)
		(property "Reference" "C1240"
			(at 0 0 0)
			(layer "B.SilkS")
			(hide yes)
			(effects
				(font
					(size 1.27 1.27)
				)
				(justify mirror)
			)
		)
		(property "Value" ""
			(at 0 0 0)
			(layer "B.Fab")
			(effects
				(font
					(size 1.27 1.27)
				)
				(justify mirror)
			)
		)
		(duplicate_pad_numbers_are_jumpers no)
		(fp_line
			(start 0.7874 0.4064)
			(end 0.7874 -0.4064)
			(stroke
				(width 0.1524)
				(type default)
			)
			(layer "B.SilkS")
		)
		(fp_line
			(start 0.7874 -0.4064)
			(end -0.7874 -0.4064)
			(stroke
				(width 0.1524)
				(type default)
			)
			(layer "B.SilkS")
		)
		(fp_line
			(start -0.7874 0.4064)
			(end 0.7874 0.4064)
			(stroke
				(width 0.1524)
				(type default)
			)
			(layer "B.SilkS")
		)
		(fp_line
			(start -0.7874 -0.4064)
			(end -0.7874 0.4064)
			(stroke
				(width 0.1524)
				(type default)
			)
			(layer "B.SilkS")
		)
		(fp_line
			(start 0.67945 0.3048)
			(end 0.67945 -0.305054)
			(stroke
				(width 0.1)
				(type default)
			)
			(layer "B.Fab")
		)
		(fp_line
			(start 0.67945 -0.305054)
			(end 0.12065 -0.305054)
			(stroke
				(width 0.1)
				(type default)
			)
			(layer "B.Fab")
		)
		(fp_line
			(start 0.12065 0.3048)
			(end 0.67945 0.3048)
			(stroke
				(width 0.1)
				(type default)
			)
			(layer "B.Fab")
		)
		(fp_line
			(start 0.12065 0.2794)
			(end 0.12065 0.3048)
			(stroke
				(width 0.1)
				(type default)
			)
			(layer "B.Fab")
		)
		(fp_line
			(start 0.12065 -0.2794)
			(end -0.12065 -0.2794)
			(stroke
				(width 0.1)
				(type default)
			)
			(layer "B.Fab")
		)
		(fp_line
			(start 0.12065 -0.305054)
			(end 0.12065 -0.2794)
			(stroke
				(width 0.1)
				(type default)
			)
			(layer "B.Fab")
		)
		(fp_line
			(start -0.120396 0.3048)
			(end -0.120396 0.2794)
			(stroke
				(width 0.1)
				(type default)
			)
			(layer "B.Fab")
		)
		(fp_line
			(start -0.120396 0.2794)
			(end 0.12065 0.2794)
			(stroke
				(width 0.1)
				(type default)
			)
			(layer "B.Fab")
		)
		(fp_line
			(start -0.12065 -0.2794)
			(end -0.12065 -0.3048)
			(stroke
				(width 0.1)
				(type default)
			)
			(layer "B.Fab")
		)
		(fp_line
			(start -0.12065 -0.3048)
			(end -0.67945 -0.3048)
			(stroke
				(width 0.1)
				(type default)
			)
			(layer "B.Fab")
		)
		(fp_line
			(start -0.67945 0.3048)
			(end -0.120396 0.3048)
			(stroke
				(width 0.1)
				(type default)
			)
			(layer "B.Fab")
		)
		(fp_line
			(start -0.67945 -0.3048)
			(end -0.67945 0.3048)
			(stroke
				(width 0.1)
				(type default)
			)
			(layer "B.Fab")
		)
		(pad "1" smd circle
			(at 0.40005 0)
			(size 0 0)
			(layers "B.Cu" "B.Mask" "B.Paste")
			(net "P3V3_OCP_SFF")
		)
		(pad "2" smd circle
			(at -0.40005 0)
			(size 0 0)
			(layers "B.Cu" "B.Mask" "B.Paste")
			(net "GND")
		)
	)
)
